(kicad_pcb
	(version 20260206)
	(generator "pcbnew")
	(generator_version "10.0")
	(general
		(thickness 1.6)
		(legacy_teardrops no)
	)
	(paper "A4")
	(title_block
		(title "12092022_DA0F0TMDCD0_F0T_Management_Board_D_brd_V3_OCP.brd")
		(comment 1 "Grand Teton / footprints 43-48 of 1440")
	)
	(layers
		(0 "F.Cu" signal "TOP")
		(4 "In1.Cu" signal "GND")
		(6 "In2.Cu" signal "IN1")
		(8 "In3.Cu" signal "GND1")
		(10 "In4.Cu" signal "IN2")
		(12 "In5.Cu" signal "VCC")
		(14 "In6.Cu" signal "VCC1")
		(16 "In7.Cu" signal "IN3")
		(18 "In8.Cu" signal "GND2")
		(20 "In9.Cu" signal "IN4")
		(22 "In10.Cu" signal "GND3")
		(2 "B.Cu" signal "BOTTOM")
		(9 "F.Adhes" user "F.Adhesive")
		(11 "B.Adhes" user "B.Adhesive")
		(13 "F.Paste" user "Package Geometry/Pastemask Top")
		(15 "B.Paste" user "Package Geometry/Pastemask Bottom")
		(5 "F.SilkS" user "Ref Des/Silkscreen Top")
		(7 "B.SilkS" user "Ref Des/Silkscreen Bottom")
		(1 "F.Mask" user "Board Geometry/Soldermask Top")
		(3 "B.Mask" user "Board Geometry/Soldermask Bottom")
		(17 "Dwgs.User" user "User.Drawings")
		(19 "Cmts.User" user "User.Comments")
		(21 "Eco1.User" user "User.Eco1")
		(23 "Eco2.User" user "User.Eco2")
		(25 "Edge.Cuts" user "Board Geometry/Outline")
		(27 "Margin" user)
		(31 "F.CrtYd" user "Package Geometry/Place Bound Top")
		(29 "B.CrtYd" user "Package Geometry/Place Bound Bottom")
		(35 "F.Fab" user "Ref Des/Assembly Top")
		(33 "B.Fab" user "Ref Des/Assembly Bottom")
	)
	(footprint ""
		(layer "F.Cu")
		(at 49.657 -67.26174 180)
		(property "Reference" "R209"
			(at 0 0 180)
			(layer "F.SilkS")
			(hide yes)
			(effects
				(font
					(size 1.27 1.27)
				)
			)
		)
		(property "Value" ""
			(at 0 0 180)
			(layer "F.Fab")
			(effects
				(font
					(size 1.27 1.27)
				)
			)
		)
		(duplicate_pad_numbers_are_jumpers no)
		(fp_line
			(start 0.7874 0.4064)
			(end -0.7874 0.4064)
			(stroke
				(width 0.1524)
				(type default)
			)
			(layer "F.SilkS")
		)
		(fp_line
			(start 0.7874 -0.4064)
			(end 0.7874 0.4064)
			(stroke
				(width 0.1524)
				(type default)
			)
			(layer "F.SilkS")
		)
		(fp_line
			(start -0.7874 0.4064)
			(end -0.7874 -0.4064)
			(stroke
				(width 0.1524)
				(type default)
			)
			(layer "F.SilkS")
		)
		(fp_line
			(start -0.7874 -0.4064)
			(end 0.7874 -0.4064)
			(stroke
				(width 0.1524)
				(type default)
			)
			(layer "F.SilkS")
		)
		(fp_line
			(start 0.67945 0.3048)
			(end 0.120396 0.3048)
			(stroke
				(width 0.1)
				(type default)
			)
			(layer "F.Fab")
		)
		(fp_line
			(start 0.67945 -0.3048)
			(end 0.67945 0.3048)
			(stroke
				(width 0.1)
				(type default)
			)
			(layer "F.Fab")
		)
		(fp_line
			(start 0.12065 -0.2794)
			(end 0.12065 -0.3048)
			(stroke
				(width 0.1)
				(type default)
			)
			(layer "F.Fab")
		)
		(fp_line
			(start 0.12065 -0.3048)
			(end 0.67945 -0.3048)
			(stroke
				(width 0.1)
				(type default)
			)
			(layer "F.Fab")
		)
		(fp_line
			(start 0.120396 0.3048)
			(end 0.120396 0.2794)
			(stroke
				(width 0.1)
				(type default)
			)
			(layer "F.Fab")
		)
		(fp_line
			(start 0.120396 0.2794)
			(end -0.12065 0.2794)
			(stroke
				(width 0.1)
				(type default)
			)
			(layer "F.Fab")
		)
		(fp_line
			(start -0.12065 0.3048)
			(end -0.67945 0.3048)
			(stroke
				(width 0.1)
				(type default)
			)
			(layer "F.Fab")
		)
		(fp_line
			(start -0.12065 0.2794)
			(end -0.12065 0.3048)
			(stroke
				(width 0.1)
				(type default)
			)
			(layer "F.Fab")
		)
		(fp_line
			(start -0.12065 -0.2794)
			(end 0.12065 -0.2794)
			(stroke
				(width 0.1)
				(type default)
			)
			(layer "F.Fab")
		)
		(fp_line
			(start -0.12065 -0.305054)
			(end -0.12065 -0.2794)
			(stroke
				(width 0.1)
				(type default)
			)
			(layer "F.Fab")
		)
		(fp_line
			(start -0.67945 0.3048)
			(end -0.67945 -0.305054)
			(stroke
				(width 0.1)
				(type default)
			)
			(layer "F.Fab")
		)
		(fp_line
			(start -0.67945 -0.305054)
			(end -0.12065 -0.305054)
			(stroke
				(width 0.1)
				(type default)
			)
			(layer "F.Fab")
		)
		(pad "1" smd circle
			(at -0.40005 0 180)
			(size 0 0)
			(layers "F.Cu" "F.Mask" "F.Paste")
			(net "PECI_BMC")
		)
		(pad "2" smd circle
			(at 0.40005 0 180)
			(size 0 0)
			(layers "F.Cu" "F.Mask" "F.Paste")
			(net "GND")
		)
	)
	(footprint ""
		(layer "F.Cu")
		(at 51.84648 -34.637726 90)
		(property "Reference" "R236"
			(at 0 0 90)
			(layer "F.SilkS")
			(hide yes)
			(effects
				(font
					(size 1.27 1.27)
				)
			)
		)
		(property "Value" ""
			(at 0 0 90)
			(layer "F.Fab")
			(effects
				(font
					(size 1.27 1.27)
				)
			)
		)
		(duplicate_pad_numbers_are_jumpers no)
		(fp_line
			(start 0.7874 -0.4064)
			(end 0.7874 0.4064)
			(stroke
				(width 0.1524)
				(type default)
			)
			(layer "F.SilkS")
		)
		(fp_line
			(start -0.7874 -0.4064)
			(end 0.7874 -0.4064)
			(stroke
				(width 0.1524)
				(type default)
			)
			(layer "F.SilkS")
		)
		(fp_line
			(start 0.7874 0.4064)
			(end -0.7874 0.4064)
			(stroke
				(width 0.1524)
				(type default)
			)
			(layer "F.SilkS")
		)
		(fp_line
			(start -0.7874 0.4064)
			(end -0.7874 -0.4064)
			(stroke
				(width 0.1524)
				(type default)
			)
			(layer "F.SilkS")
		)
		(fp_line
			(start -0.12065 -0.305054)
			(end -0.12065 -0.2794)
			(stroke
				(width 0.1)
				(type default)
			)
			(layer "F.Fab")
		)
		(fp_line
			(start -0.67945 -0.305054)
			(end -0.12065 -0.305054)
			(stroke
				(width 0.1)
				(type default)
			)
			(layer "F.Fab")
		)
		(fp_line
			(start 0.67945 -0.3048)
			(end 0.67945 0.3048)
			(stroke
				(width 0.1)
				(type default)
			)
			(layer "F.Fab")
		)
		(fp_line
			(start 0.12065 -0.3048)
			(end 0.67945 -0.3048)
			(stroke
				(width 0.1)
				(type default)
			)
			(layer "F.Fab")
		)
		(fp_line
			(start 0.12065 -0.2794)
			(end 0.12065 -0.3048)
			(stroke
				(width 0.1)
				(type default)
			)
			(layer "F.Fab")
		)
		(fp_line
			(start -0.12065 -0.2794)
			(end 0.12065 -0.2794)
			(stroke
				(width 0.1)
				(type default)
			)
			(layer "F.Fab")
		)
		(fp_line
			(start 0.120396 0.2794)
			(end -0.12065 0.2794)
			(stroke
				(width 0.1)
				(type default)
			)
			(layer "F.Fab")
		)
		(fp_line
			(start -0.12065 0.2794)
			(end -0.12065 0.3048)
			(stroke
				(width 0.1)
				(type default)
			)
			(layer "F.Fab")
		)
		(fp_line
			(start 0.67945 0.3048)
			(end 0.120396 0.3048)
			(stroke
				(width 0.1)
				(type default)
			)
			(layer "F.Fab")
		)
		(fp_line
			(start 0.120396 0.3048)
			(end 0.120396 0.2794)
			(stroke
				(width 0.1)
				(type default)
			)
			(layer "F.Fab")
		)
		(fp_line
			(start -0.12065 0.3048)
			(end -0.67945 0.3048)
			(stroke
				(width 0.1)
				(type default)
			)
			(layer "F.Fab")
		)
		(fp_line
			(start -0.67945 0.3048)
			(end -0.67945 -0.305054)
			(stroke
				(width 0.1)
				(type default)
			)
			(layer "F.Fab")
		)
		(pad "1" smd circle
			(at -0.40005 0 90)
			(size 0 0)
			(layers "F.Cu" "F.Mask" "F.Paste")
			(net "SMB_BMC_MM15_SDA")
		)
		(pad "2" smd circle
			(at 0.40005 0 90)
			(size 0 0)
			(layers "F.Cu" "F.Mask" "F.Paste")
			(net "SMB_BMC_MM15_R_SDA")
		)
	)
	(footprint ""
		(layer "F.Cu")
		(at 20.447 -40.259 -90)
		(property "Reference" "PL32"
			(at 0 0 270)
			(layer "F.SilkS")
			(hide yes)
			(effects
				(font
					(size 1.27 1.27)
				)
			)
		)
		(property "Value" ""
			(at 0 0 270)
			(layer "F.Fab")
			(effects
				(font
					(size 1.27 1.27)
				)
			)
		)
		(duplicate_pad_numbers_are_jumpers no)
		(fp_line
			(start -1.27 0.5842)
			(end -1.27 -0.5842)
			(stroke
				(width 0.1524)
				(type default)
			)
			(layer "F.SilkS")
		)
		(fp_line
			(start -0.127 0.5842)
			(end -0.127 -0.5842)
			(stroke
				(width 0.1524)
				(type default)
			)
			(layer "F.SilkS")
		)
		(fp_line
			(start 0.127 0.5842)
			(end 0.127 -0.5842)
			(stroke
				(width 0.1524)
				(type default)
			)
			(layer "F.SilkS")
		)
		(fp_line
			(start 1.27 0.5842)
			(end -1.27 0.5842)
			(stroke
				(width 0.1524)
				(type default)
			)
			(layer "F.SilkS")
		)
		(fp_line
			(start 1.27 0.5842)
			(end 1.27 -0.5842)
			(stroke
				(width 0.1524)
				(type default)
			)
			(layer "F.SilkS")
		)
		(fp_line
			(start -1.27 -0.5588)
			(end -1.27 -0.5842)
			(stroke
				(width 0.1524)
				(type default)
			)
			(layer "F.SilkS")
		)
		(fp_line
			(start -1.27 -0.5842)
			(end 1.27 -0.5842)
			(stroke
				(width 0.1524)
				(type default)
			)
			(layer "F.SilkS")
		)
		(fp_line
			(start -0.9144 0.508)
			(end -0.9144 0.406654)
			(stroke
				(width 0.1)
				(type default)
			)
			(layer "F.Fab")
		)
		(fp_line
			(start 0.9144 0.508)
			(end -0.9144 0.508)
			(stroke
				(width 0.1)
				(type default)
			)
			(layer "F.Fab")
		)
		(fp_line
			(start -1.194308 0.406654)
			(end -1.194308 -0.406654)
			(stroke
				(width 0.1)
				(type default)
			)
			(layer "F.Fab")
		)
		(fp_line
			(start -0.9144 0.406654)
			(end -1.194308 0.406654)
			(stroke
				(width 0.1)
				(type default)
			)
			(layer "F.Fab")
		)
		(fp_line
			(start 0.9144 0.4064)
			(end 0.9144 0.508)
			(stroke
				(width 0.1)
				(type default)
			)
			(layer "F.Fab")
		)
		(fp_line
			(start 1.1938 0.4064)
			(end 0.9144 0.4064)
			(stroke
				(width 0.1)
				(type default)
			)
			(layer "F.Fab")
		)
		(fp_line
			(start -1.194308 -0.406654)
			(end -0.9144 -0.406654)
			(stroke
				(width 0.1)
				(type default)
			)
			(layer "F.Fab")
		)
		(fp_line
			(start -0.9144 -0.406654)
			(end -0.9144 -0.508)
			(stroke
				(width 0.1)
				(type default)
			)
			(layer "F.Fab")
		)
		(fp_line
			(start 0.9144 -0.406654)
			(end 1.1938 -0.406654)
			(stroke
				(width 0.1)
				(type default)
			)
			(layer "F.Fab")
		)
		(fp_line
			(start 1.1938 -0.406654)
			(end 1.1938 0.4064)
			(stroke
				(width 0.1)
				(type default)
			)
			(layer "F.Fab")
		)
		(fp_line
			(start -0.9144 -0.508)
			(end 0.9144 -0.508)
			(stroke
				(width 0.1)
				(type default)
			)
			(layer "F.Fab")
		)
		(fp_line
			(start 0.9144 -0.508)
			(end 0.9144 -0.406654)
			(stroke
				(width 0.1)
				(type default)
			)
			(layer "F.Fab")
		)
		(pad "1" smd rect
			(at -0.7366 0 180)
			(size 0.7112 0.8128)
			(layers "F.Cu" "F.Mask" "F.Paste")
			(net "P12V_AUX")
		)
		(pad "2" smd rect
			(at 0.7366 0 180)
			(size 0.7112 0.8128)
			(layers "F.Cu" "F.Mask" "F.Paste")
			(net "SW_P1V0_AUX_FLT")
		)
	)
	(footprint ""
		(layer "F.Cu")
		(at 26.75001 -47.389034)
		(property "Reference" "H2"
			(at -2.4892 -4.562348 0)
			(unlocked yes)
			(layer "F.SilkS")
			(effects
				(font
					(size 0.7874 0.5842)
					(thickness 0.1524)
				)
			)
		)
		(property "Value" ""
			(at 0 0 0)
			(layer "F.Fab")
			(effects
				(font
					(size 1.27 1.27)
				)
			)
		)
		(duplicate_pad_numbers_are_jumpers no)
		(pad "" np_thru_hole circle
			(at 0 0)
			(size 0 0)
			(drill oval 3.2004 4.8006)
			(layers "*.Cu" "*.Mask")
			(clearance -1.2192)
			(thermal_gap 0.381)
			(padstack
				(mode front_inner_back)
				(layer "Inner"
					(shape oval)
					(size 3.2004 4.8006)
					(clearance 0.381)
				)
				(layer "B.Cu"
					(shape circle)
					(size 0 0)
					(clearance -1.2192)
				)
			)
		)
		(zone
			(layers "F.Cu" "B.Cu" "In1.Cu" "In2.Cu" "In3.Cu" "In4.Cu" "In5.Cu" "In6.Cu"
				"In7.Cu" "In8.Cu" "In9.Cu" "In10.Cu"
			)
			(hatch none 0.5)
			(connect_pads
				(clearance 0)
			)
			(min_thickness 0.25)
			(keepout
				(tracks not_allowed)
				(vias allowed)
				(pads allowed)
				(copperpour not_allowed)
				(footprints allowed)
			)
			(placement
				(enabled no)
				(sheetname "")
			)
			(fill
				(thermal_gap 0.5)
				(thermal_bridge_width 0.5)
				(island_removal_mode 0)
			)
			(polygon
				(pts
					(arc
						(start 28.85821 -46.588934)
						(mid 26.75001 -44.480734)
						(end 24.64181 -46.588934)
					)
					(arc
						(start 24.64181 -48.189134)
						(mid 26.75001 -50.297334)
						(end 28.85821 -48.189134)
					)
				)
			)
		)
		(zone
			(layers "F.Cu" "B.Cu" "In1.Cu" "In2.Cu" "In3.Cu" "In4.Cu" "In5.Cu" "In6.Cu"
				"In7.Cu" "In8.Cu" "In9.Cu" "In10.Cu"
			)
			(hatch none 0.5)
			(connect_pads
				(clearance 0)
			)
			(min_thickness 0.25)
			(keepout
				(tracks not_allowed)
				(vias allowed)
				(pads allowed)
				(copperpour not_allowed)
				(footprints allowed)
			)
			(placement
				(enabled no)
				(sheetname "")
			)
			(fill
				(thermal_gap 0.5)
				(thermal_bridge_width 0.5)
				(island_removal_mode 0)
			)
			(polygon
				(pts
					(arc
						(start 29.750258 -46.588934)
						(mid 26.75001 -43.588686)
						(end 23.749762 -46.588934)
					)
					(arc
						(start 23.749762 -48.189134)
						(mid 26.75001 -51.189382)
						(end 29.750258 -48.189134)
					)
				)
			)
		)
	)
	(footprint ""
		(layer "F.Cu")
		(at 23.241 -64.897)
		(property "Reference" "R396"
			(at 0 0 0)
			(layer "F.SilkS")
			(hide yes)
			(effects
				(font
					(size 1.27 1.27)
				)
			)
		)
		(property "Value" ""
			(at 0 0 0)
			(layer "F.Fab")
			(effects
				(font
					(size 1.27 1.27)
				)
			)
		)
		(duplicate_pad_numbers_are_jumpers no)
		(fp_line
			(start -0.7874 -0.4064)
			(end 0.7874 -0.4064)
			(stroke
				(width 0.1524)
				(type default)
			)
			(layer "F.SilkS")
		)
		(fp_line
			(start -0.7874 0.4064)
			(end -0.7874 -0.4064)
			(stroke
				(width 0.1524)
				(type default)
			)
			(layer "F.SilkS")
		)
		(fp_line
			(start 0.7874 -0.4064)
			(end 0.7874 0.4064)
			(stroke
				(width 0.1524)
				(type default)
			)
			(layer "F.SilkS")
		)
		(fp_line
			(start 0.7874 0.4064)
			(end -0.7874 0.4064)
			(stroke
				(width 0.1524)
				(type default)
			)
			(layer "F.SilkS")
		)
		(fp_line
			(start -0.67945 -0.305054)
			(end -0.12065 -0.305054)
			(stroke
				(width 0.1)
				(type default)
			)
			(layer "F.Fab")
		)
		(fp_line
			(start -0.67945 0.3048)
			(end -0.67945 -0.305054)
			(stroke
				(width 0.1)
				(type default)
			)
			(layer "F.Fab")
		)
		(fp_line
			(start -0.12065 -0.305054)
			(end -0.12065 -0.2794)
			(stroke
				(width 0.1)
				(type default)
			)
			(layer "F.Fab")
		)
		(fp_line
			(start -0.12065 -0.2794)
			(end 0.12065 -0.2794)
			(stroke
				(width 0.1)
				(type default)
			)
			(layer "F.Fab")
		)
		(fp_line
			(start -0.12065 0.2794)
			(end -0.12065 0.3048)
			(stroke
				(width 0.1)
				(type default)
			)
			(layer "F.Fab")
		)
		(fp_line
			(start -0.12065 0.3048)
			(end -0.67945 0.3048)
			(stroke
				(width 0.1)
				(type default)
			)
			(layer "F.Fab")
		)
		(fp_line
			(start 0.120396 0.2794)
			(end -0.12065 0.2794)
			(stroke
				(width 0.1)
				(type default)
			)
			(layer "F.Fab")
		)
		(fp_line
			(start 0.120396 0.3048)
			(end 0.120396 0.2794)
			(stroke
				(width 0.1)
				(type default)
			)
			(layer "F.Fab")
		)
		(fp_line
			(start 0.12065 -0.3048)
			(end 0.67945 -0.3048)
			(stroke
				(width 0.1)
				(type default)
			)
			(layer "F.Fab")
		)
		(fp_line
			(start 0.12065 -0.2794)
			(end 0.12065 -0.3048)
			(stroke
				(width 0.1)
				(type default)
			)
			(layer "F.Fab")
		)
		(fp_line
			(start 0.67945 -0.3048)
			(end 0.67945 0.3048)
			(stroke
				(width 0.1)
				(type default)
			)
			(layer "F.Fab")
		)
		(fp_line
			(start 0.67945 0.3048)
			(end 0.120396 0.3048)
			(stroke
				(width 0.1)
				(type default)
			)
			(layer "F.Fab")
		)
		(pad "1" smd circle
			(at -0.40005 0)
			(size 0 0)
			(layers "F.Cu" "F.Mask" "F.Paste")
			(net "P3V3_AUX")
		)
		(pad "2" smd circle
			(at 0.40005 0)
			(size 0 0)
			(layers "F.Cu" "F.Mask" "F.Paste")
			(net "UART_BIC_GF_RXD")
		)
	)
	(footprint ""
		(layer "F.Cu")
		(at 72.46493 -30.957774 -90)
		(property "Reference" "R597"
			(at 0 0 270)
			(layer "F.SilkS")
			(hide yes)
			(effects
				(font
					(size 1.27 1.27)
				)
			)
		)
		(property "Value" ""
			(at 0 0 270)
			(layer "F.Fab")
			(effects
				(font
					(size 1.27 1.27)
				)
			)
		)
		(duplicate_pad_numbers_are_jumpers no)
		(fp_line
			(start -0.7874 0.4064)
			(end -0.7874 -0.4064)
			(stroke
				(width 0.1524)
				(type default)
			)
			(layer "F.SilkS")
		)
		(fp_line
			(start 0.7874 0.4064)
			(end -0.7874 0.4064)
			(stroke
				(width 0.1524)
				(type default)
			)
			(layer "F.SilkS")
		)
		(fp_line
			(start -0.7874 -0.4064)
			(end 0.7874 -0.4064)
			(stroke
				(width 0.1524)
				(type default)
			)
			(layer "F.SilkS")
		)
		(fp_line
			(start 0.7874 -0.4064)
			(end 0.7874 0.4064)
			(stroke
				(width 0.1524)
				(type default)
			)
			(layer "F.SilkS")
		)
		(fp_line
			(start -0.67945 0.3048)
			(end -0.67945 -0.305054)
			(stroke
				(width 0.1)
				(type default)
			)
			(layer "F.Fab")
		)
		(fp_line
			(start -0.12065 0.3048)
			(end -0.67945 0.3048)
			(stroke
				(width 0.1)
				(type default)
			)
			(layer "F.Fab")
		)
		(fp_line
			(start 0.120396 0.3048)
			(end 0.120396 0.2794)
			(stroke
				(width 0.1)
				(type default)
			)
			(layer "F.Fab")
		)
		(fp_line
			(start 0.67945 0.3048)
			(end 0.120396 0.3048)
			(stroke
				(width 0.1)
				(type default)
			)
			(layer "F.Fab")
		)
		(fp_line
			(start -0.12065 0.2794)
			(end -0.12065 0.3048)
			(stroke
				(width 0.1)
				(type default)
			)
			(layer "F.Fab")
		)
		(fp_line
			(start 0.120396 0.2794)
			(end -0.12065 0.2794)
			(stroke
				(width 0.1)
				(type default)
			)
			(layer "F.Fab")
		)
		(fp_line
			(start -0.12065 -0.2794)
			(end 0.12065 -0.2794)
			(stroke
				(width 0.1)
				(type default)
			)
			(layer "F.Fab")
		)
		(fp_line
			(start 0.12065 -0.2794)
			(end 0.12065 -0.3048)
			(stroke
				(width 0.1)
				(type default)
			)
			(layer "F.Fab")
		)
		(fp_line
			(start 0.12065 -0.3048)
			(end 0.67945 -0.3048)
			(stroke
				(width 0.1)
				(type default)
			)
			(layer "F.Fab")
		)
		(fp_line
			(start 0.67945 -0.3048)
			(end 0.67945 0.3048)
			(stroke
				(width 0.1)
				(type default)
			)
			(layer "F.Fab")
		)
		(fp_line
			(start -0.67945 -0.305054)
			(end -0.12065 -0.305054)
			(stroke
				(width 0.1)
				(type default)
			)
			(layer "F.Fab")
		)
		(fp_line
			(start -0.12065 -0.305054)
			(end -0.12065 -0.2794)
			(stroke
				(width 0.1)
				(type default)
			)
			(layer "F.Fab")
		)
		(pad "1" smd circle
			(at -0.40005 0 270)
			(size 0 0)
			(layers "F.Cu" "F.Mask" "F.Paste")
			(net "LED_POSTCODE_7")
		)
		(pad "2" smd circle
			(at 0.40005 0 270)
			(size 0 0)
			(layers "F.Cu" "F.Mask" "F.Paste")
			(net "LED_POSTCODE_7_R")
		)
	)
)
